(kicad_pcb
	(version 20241229)
	(generator "pcbnew")
	(generator_version "9.0")
	(general
		(thickness 1.599998)
		(legacy_teardrops no)
	)
	(paper "A4")
	(title_block
		(date "2023-02-12")
		(rev "1.1.5")
		(comment 9 "footprints 443-449 of 473")
	)
	(layers
		(0 "F.Cu" signal)
		(4 "In1.Cu" power "In1.GND")
		(6 "In2.Cu" signal)
		(8 "In3.Cu" power "In3.GND")
		(10 "In4.Cu" power "In4.VCC")
		(12 "In5.Cu" signal)
		(14 "In6.Cu" power "In6.VCC")
		(2 "B.Cu" signal)
		(9 "F.Adhes" user "F.Adhesive")
		(11 "B.Adhes" user "B.Adhesive")
		(13 "F.Paste" user)
		(15 "B.Paste" user)
		(5 "F.SilkS" user "F.Silkscreen")
		(7 "B.SilkS" user "B.Silkscreen")
		(1 "F.Mask" user)
		(3 "B.Mask" user)
		(17 "Dwgs.User" user "User.Drawings")
		(19 "Cmts.User" user "User.Comments")
		(21 "Eco1.User" user "User.Eco1")
		(23 "Eco2.User" user "User.Eco2")
		(25 "Edge.Cuts" user)
		(27 "Margin" user)
		(31 "F.CrtYd" user "F.Courtyard")
		(29 "B.CrtYd" user "B.Courtyard")
		(35 "F.Fab" user)
		(33 "B.Fab" user)
	)
	(footprint "antmicro-footprints:R_0402_1005Metric"
		(layer "B.Cu")
		(at 198.786328 95.120008 90)
		(descr "Resistor SMD 0402")
		(tags "resistor SMD 0402")
		(property "Reference" "R74"
			(at 2.920008 0.413672 270)
			(layer "B.SilkS")
			(effects
				(font
					(size 0.7 0.7)
					(thickness 0.15)
				)
				(justify left bottom mirror)
			)
		)
		(property "Value" "R_10k2_0402"
			(at 0 -1.4 270)
			(layer "B.Fab")
			(effects
				(font
					(size 0.7 0.7)
					(thickness 0.15)
				)
				(justify left bottom mirror)
			)
		)
		(property "Description" "10k2 resistor in 0402 package with 1% tolerance"
			(at 0 0 90)
			(layer "F.Fab")
			(hide yes)
			(effects
				(font
					(size 1.27 1.27)
					(thickness 0.15)
				)
			)
		)
		(property "Author" "Antmicro"
			(at 293.906336 -103.66632 0)
			(layer "B.Fab")
			(hide yes)
			(effects
				(font
					(size 1 1)
					(thickness 0.15)
				)
				(justify mirror)
			)
		)
		(property "License" "Apache-2.0"
			(at 293.906336 -103.66632 0)
			(layer "B.Fab")
			(hide yes)
			(effects
				(font
					(size 1 1)
					(thickness 0.15)
				)
				(justify mirror)
			)
		)
		(property "MPN" "CR0402-FX-1022GLF"
			(at 293.906336 -103.66632 0)
			(layer "B.Fab")
			(hide yes)
			(effects
				(font
					(size 1 1)
					(thickness 0.15)
				)
				(justify mirror)
			)
		)
		(property "Manufacturer" "Bourns"
			(at 293.906336 -103.66632 0)
			(layer "B.Fab")
			(hide yes)
			(effects
				(font
					(size 1 1)
					(thickness 0.15)
				)
				(justify mirror)
			)
		)
		(property "Tolerance" "1%"
			(at 293.906336 -103.66632 0)
			(layer "B.Fab")
			(hide yes)
			(effects
				(font
					(size 1 1)
					(thickness 0.15)
				)
				(justify mirror)
			)
		)
		(property "Val" "10k2"
			(at 293.906336 -103.66632 0)
			(layer "B.Fab")
			(hide yes)
			(effects
				(font
					(size 1 1)
					(thickness 0.15)
				)
				(justify mirror)
			)
		)
		(sheetname "Ethernet")
		(sheetfile "ethernet.kicad_sch")
		(attr exclude_from_pos_files exclude_from_bom dnp)
		(fp_rect
			(start -0.93 0.47)
			(end 0.93 -0.47)
			(stroke
				(width 0.05)
				(type solid)
			)
			(fill no)
			(layer "B.CrtYd")
		)
		(fp_rect
			(start -0.5 0.25)
			(end 0.5 -0.25)
			(stroke
				(width 0.15)
				(type solid)
			)
			(fill no)
			(layer "B.Fab")
		)
		(pad "1" smd roundrect
			(at -0.485 0 90)
			(size 0.59 0.64)
			(layers "B.Cu" "B.Mask" "B.Paste")
			(roundrect_rratio 0.25)
			(net 22 "ETH_RXD0")
			(pintype "passive")
		)
		(pad "2" smd roundrect
			(at 0.485 0 90)
			(size 0.59 0.64)
			(layers "B.Cu" "B.Mask" "B.Paste")
			(roundrect_rratio 0.25)
			(net 459 "3V3_SYS")
			(pintype "passive")
		)
	)
	(footprint "antmicro-footprints:R_0402_1005Metric"
		(layer "B.Cu")
		(at 140.536328 92.370008 -90)
		(descr "Resistor SMD 0402")
		(tags "resistor SMD 0402")
		(property "Reference" "R107"
			(at 0.829992 -0.363672 90)
			(layer "B.SilkS")
			(effects
				(font
					(size 0.7 0.7)
					(thickness 0.15)
				)
				(justify left bottom mirror)
			)
		)
		(property "Value" "R_10k_0402"
			(at 0 -1.4 90)
			(layer "B.Fab")
			(effects
				(font
					(size 0.7 0.7)
					(thickness 0.15)
				)
				(justify left bottom mirror)
			)
		)
		(property "Description" "10k resistor in 0402 package with 1% tolerance"
			(at 0 0 270)
			(layer "F.Fab")
			(hide yes)
			(effects
				(font
					(size 1.27 1.27)
					(thickness 0.15)
				)
			)
		)
		(property "Author" "Antmicro"
			(at 48.16632 232.906336 0)
			(layer "B.Fab")
			(hide yes)
			(effects
				(font
					(size 1 1)
					(thickness 0.15)
				)
				(justify mirror)
			)
		)
		(property "License" "Apache-2.0"
			(at 48.16632 232.906336 0)
			(layer "B.Fab")
			(hide yes)
			(effects
				(font
					(size 1 1)
					(thickness 0.15)
				)
				(justify mirror)
			)
		)
		(property "MPN" "CR0402-FX-1002GLF"
			(at 48.16632 232.906336 0)
			(layer "B.Fab")
			(hide yes)
			(effects
				(font
					(size 1 1)
					(thickness 0.15)
				)
				(justify mirror)
			)
		)
		(property "Manufacturer" "Bourns"
			(at 48.16632 232.906336 0)
			(layer "B.Fab")
			(hide yes)
			(effects
				(font
					(size 1 1)
					(thickness 0.15)
				)
				(justify mirror)
			)
		)
		(property "Tolerance" "1%"
			(at 48.16632 232.906336 0)
			(layer "B.Fab")
			(hide yes)
			(effects
				(font
					(size 1 1)
					(thickness 0.15)
				)
				(justify mirror)
			)
		)
		(property "Val" "10k"
			(at 48.16632 232.906336 0)
			(layer "B.Fab")
			(hide yes)
			(effects
				(font
					(size 1 1)
					(thickness 0.15)
				)
				(justify mirror)
			)
		)
		(sheetname "Supply")
		(sheetfile "supply.kicad_sch")
		(attr smd)
		(fp_rect
			(start -0.93 0.47)
			(end 0.93 -0.47)
			(stroke
				(width 0.05)
				(type solid)
			)
			(fill no)
			(layer "B.CrtYd")
		)
		(fp_rect
			(start -0.5 0.25)
			(end 0.5 -0.25)
			(stroke
				(width 0.15)
				(type solid)
			)
			(fill no)
			(layer "B.Fab")
		)
		(pad "1" smd roundrect
			(at -0.485 0 270)
			(size 0.59 0.64)
			(layers "B.Cu" "B.Mask" "B.Paste")
			(roundrect_rratio 0.25)
			(net 463 "VCC5V0_INT")
			(pintype "passive")
		)
		(pad "2" smd roundrect
			(at 0.485 0 270)
			(size 0.59 0.64)
			(layers "B.Cu" "B.Mask" "B.Paste")
			(roundrect_rratio 0.25)
			(net 468 "/Supply/VCC_INT_EN")
			(pintype "passive")
		)
	)
	(footprint "antmicro-footprints:R_0402_1005Metric"
		(layer "B.Cu")
		(at 141.536328 92.370008 -90)
		(descr "Resistor SMD 0402")
		(tags "resistor SMD 0402")
		(property "Reference" "R108"
			(at 0.829992 -0.363672 90)
			(layer "B.SilkS")
			(effects
				(font
					(size 0.7 0.7)
					(thickness 0.15)
				)
				(justify left bottom mirror)
			)
		)
		(property "Value" "R_10k_0402"
			(at 0 -1.4 90)
			(layer "B.Fab")
			(effects
				(font
					(size 0.7 0.7)
					(thickness 0.15)
				)
				(justify left bottom mirror)
			)
		)
		(property "Description" "10k resistor in 0402 package with 1% tolerance"
			(at 0 0 270)
			(layer "F.Fab")
			(hide yes)
			(effects
				(font
					(size 1.27 1.27)
					(thickness 0.15)
				)
			)
		)
		(property "Author" "Antmicro"
			(at 49.16632 233.906336 0)
			(layer "B.Fab")
			(hide yes)
			(effects
				(font
					(size 1 1)
					(thickness 0.15)
				)
				(justify mirror)
			)
		)
		(property "License" "Apache-2.0"
			(at 49.16632 233.906336 0)
			(layer "B.Fab")
			(hide yes)
			(effects
				(font
					(size 1 1)
					(thickness 0.15)
				)
				(justify mirror)
			)
		)
		(property "MPN" "CR0402-FX-1002GLF"
			(at 49.16632 233.906336 0)
			(layer "B.Fab")
			(hide yes)
			(effects
				(font
					(size 1 1)
					(thickness 0.15)
				)
				(justify mirror)
			)
		)
		(property "Manufacturer" "Bourns"
			(at 49.16632 233.906336 0)
			(layer "B.Fab")
			(hide yes)
			(effects
				(font
					(size 1 1)
					(thickness 0.15)
				)
				(justify mirror)
			)
		)
		(property "Tolerance" "1%"
			(at 49.16632 233.906336 0)
			(layer "B.Fab")
			(hide yes)
			(effects
				(font
					(size 1 1)
					(thickness 0.15)
				)
				(justify mirror)
			)
		)
		(property "Val" "10k"
			(at 49.16632 233.906336 0)
			(layer "B.Fab")
			(hide yes)
			(effects
				(font
					(size 1 1)
					(thickness 0.15)
				)
				(justify mirror)
			)
		)
		(sheetname "Supply")
		(sheetfile "supply.kicad_sch")
		(attr smd)
		(fp_rect
			(start -0.93 0.47)
			(end 0.93 -0.47)
			(stroke
				(width 0.05)
				(type solid)
			)
			(fill no)
			(layer "B.CrtYd")
		)
		(fp_rect
			(start -0.5 0.25)
			(end 0.5 -0.25)
			(stroke
				(width 0.15)
				(type solid)
			)
			(fill no)
			(layer "B.Fab")
		)
		(pad "1" smd roundrect
			(at -0.485 0 270)
			(size 0.59 0.64)
			(layers "B.Cu" "B.Mask" "B.Paste")
			(roundrect_rratio 0.25)
			(net 463 "VCC5V0_INT")
			(pintype "passive")
		)
		(pad "2" smd roundrect
			(at 0.485 0 270)
			(size 0.59 0.64)
			(layers "B.Cu" "B.Mask" "B.Paste")
			(roundrect_rratio 0.25)
			(net 469 "/Supply/VCC_AUX_EN")
			(pintype "passive")
		)
	)
	(footprint "antmicro-footprints:R_0402_1005Metric"
		(layer "B.Cu")
		(at 142.536328 92.370008 -90)
		(descr "Resistor SMD 0402")
		(tags "resistor SMD 0402")
		(property "Reference" "R109"
			(at 0.829992 -0.363672 90)
			(layer "B.SilkS")
			(effects
				(font
					(size 0.7 0.7)
					(thickness 0.15)
				)
				(justify left bottom mirror)
			)
		)
		(property "Value" "R_10k_0402"
			(at 0 -1.4 90)
			(layer "B.Fab")
			(effects
				(font
					(size 0.7 0.7)
					(thickness 0.15)
				)
				(justify left bottom mirror)
			)
		)
		(property "Description" "10k resistor in 0402 package with 1% tolerance"
			(at 0 0 270)
			(layer "F.Fab")
			(hide yes)
			(effects
				(font
					(size 1.27 1.27)
					(thickness 0.15)
				)
			)
		)
		(property "Author" "Antmicro"
			(at 50.16632 234.906336 0)
			(layer "B.Fab")
			(hide yes)
			(effects
				(font
					(size 1 1)
					(thickness 0.15)
				)
				(justify mirror)
			)
		)
		(property "License" "Apache-2.0"
			(at 50.16632 234.906336 0)
			(layer "B.Fab")
			(hide yes)
			(effects
				(font
					(size 1 1)
					(thickness 0.15)
				)
				(justify mirror)
			)
		)
		(property "MPN" "CR0402-FX-1002GLF"
			(at 50.16632 234.906336 0)
			(layer "B.Fab")
			(hide yes)
			(effects
				(font
					(size 1 1)
					(thickness 0.15)
				)
				(justify mirror)
			)
		)
		(property "Manufacturer" "Bourns"
			(at 50.16632 234.906336 0)
			(layer "B.Fab")
			(hide yes)
			(effects
				(font
					(size 1 1)
					(thickness 0.15)
				)
				(justify mirror)
			)
		)
		(property "Tolerance" "1%"
			(at 50.16632 234.906336 0)
			(layer "B.Fab")
			(hide yes)
			(effects
				(font
					(size 1 1)
					(thickness 0.15)
				)
				(justify mirror)
			)
		)
		(property "Val" "10k"
			(at 50.16632 234.906336 0)
			(layer "B.Fab")
			(hide yes)
			(effects
				(font
					(size 1 1)
					(thickness 0.15)
				)
				(justify mirror)
			)
		)
		(sheetname "Supply")
		(sheetfile "supply.kicad_sch")
		(attr smd)
		(fp_rect
			(start -0.93 0.47)
			(end 0.93 -0.47)
			(stroke
				(width 0.05)
				(type solid)
			)
			(fill no)
			(layer "B.CrtYd")
		)
		(fp_rect
			(start -0.5 0.25)
			(end 0.5 -0.25)
			(stroke
				(width 0.15)
				(type solid)
			)
			(fill no)
			(layer "B.Fab")
		)
		(pad "1" smd roundrect
			(at -0.485 0 270)
			(size 0.59 0.64)
			(layers "B.Cu" "B.Mask" "B.Paste")
			(roundrect_rratio 0.25)
			(net 463 "VCC5V0_INT")
			(pintype "passive")
		)
		(pad "2" smd roundrect
			(at 0.485 0 270)
			(size 0.59 0.64)
			(layers "B.Cu" "B.Mask" "B.Paste")
			(roundrect_rratio 0.25)
			(net 470 "/Supply/VCC_IO_EN")
			(pintype "passive")
		)
	)
	(footprint "antmicro-footprints:R_0402_1005Metric"
		(layer "B.Cu")
		(at 196.686328 96.760008 -90)
		(descr "Resistor SMD 0402")
		(tags "resistor SMD 0402")
		(property "Reference" "R86"
			(at 0.739992 2.486328 270)
			(layer "B.SilkS")
			(effects
				(font
					(size 0.7 0.7)
					(thickness 0.15)
				)
				(justify left bottom mirror)
			)
		)
		(property "Value" "R_2k2_0402"
			(at 0 -1.4 90)
			(layer "B.Fab")
			(effects
				(font
					(size 0.7 0.7)
					(thickness 0.15)
				)
				(justify left bottom mirror)
			)
		)
		(property "Description" "2k2 resistor in 0402 package with 1% tolerance"
			(at 0 0 270)
			(layer "F.Fab")
			(hide yes)
			(effects
				(font
					(size 1.27 1.27)
					(thickness 0.15)
				)
			)
		)
		(property "Author" "Antmicro"
			(at 99.92632 293.446336 0)
			(layer "B.Fab")
			(hide yes)
			(effects
				(font
					(size 1 1)
					(thickness 0.15)
				)
				(justify mirror)
			)
		)
		(property "License" "Apache-2.0"
			(at 99.92632 293.446336 0)
			(layer "B.Fab")
			(hide yes)
			(effects
				(font
					(size 1 1)
					(thickness 0.15)
				)
				(justify mirror)
			)
		)
		(property "MPN" "CR0402-FX-2201GLF"
			(at 99.92632 293.446336 0)
			(layer "B.Fab")
			(hide yes)
			(effects
				(font
					(size 1 1)
					(thickness 0.15)
				)
				(justify mirror)
			)
		)
		(property "Manufacturer" "Bourns"
			(at 99.92632 293.446336 0)
			(layer "B.Fab")
			(hide yes)
			(effects
				(font
					(size 1 1)
					(thickness 0.15)
				)
				(justify mirror)
			)
		)
		(property "Tolerance" "1%"
			(at 99.92632 293.446336 0)
			(layer "B.Fab")
			(hide yes)
			(effects
				(font
					(size 1 1)
					(thickness 0.15)
				)
				(justify mirror)
			)
		)
		(property "Val" "2k2"
			(at 99.92632 293.446336 0)
			(layer "B.Fab")
			(hide yes)
			(effects
				(font
					(size 1 1)
					(thickness 0.15)
				)
				(justify mirror)
			)
		)
		(sheetname "Ethernet")
		(sheetfile "ethernet.kicad_sch")
		(attr smd)
		(fp_rect
			(start -0.93 0.47)
			(end 0.93 -0.47)
			(stroke
				(width 0.05)
				(type solid)
			)
			(fill no)
			(layer "B.CrtYd")
		)
		(fp_rect
			(start -0.5 0.25)
			(end 0.5 -0.25)
			(stroke
				(width 0.15)
				(type solid)
			)
			(fill no)
			(layer "B.Fab")
		)
		(pad "1" smd roundrect
			(at -0.485 0 270)
			(size 0.59 0.64)
			(layers "B.Cu" "B.Mask" "B.Paste")
			(roundrect_rratio 0.25)
			(net 23 "ETH_RXD1")
			(pintype "passive")
		)
		(pad "2" smd roundrect
			(at 0.485 0 270)
			(size 0.59 0.64)
			(layers "B.Cu" "B.Mask" "B.Paste")
			(roundrect_rratio 0.25)
			(net 5 "GND")
			(pintype "passive")
		)
	)
	(footprint "antmicro-footprints:R_0402_1005Metric"
		(layer "B.Cu")
		(at 197.686328 96.280008 -90)
		(descr "Resistor SMD 0402")
		(tags "resistor SMD 0402")
		(property "Reference" "R87"
			(at 0.719992 -0.513672 90)
			(layer "B.SilkS")
			(effects
				(font
					(size 0.7 0.7)
					(thickness 0.15)
				)
				(justify left bottom mirror)
			)
		)
		(property "Value" "R_2k2_0402"
			(at 0 -1.4 90)
			(layer "B.Fab")
			(effects
				(font
					(size 0.7 0.7)
					(thickness 0.15)
				)
				(justify left bottom mirror)
			)
		)
		(property "Description" "2k2 resistor in 0402 package with 1% tolerance"
			(at 0 0 270)
			(layer "F.Fab")
			(hide yes)
			(effects
				(font
					(size 1.27 1.27)
					(thickness 0.15)
				)
			)
		)
		(property "Author" "Antmicro"
			(at 101.40632 293.966336 0)
			(layer "B.Fab")
			(hide yes)
			(effects
				(font
					(size 1 1)
					(thickness 0.15)
				)
				(justify mirror)
			)
		)
		(property "License" "Apache-2.0"
			(at 101.40632 293.966336 0)
			(layer "B.Fab")
			(hide yes)
			(effects
				(font
					(size 1 1)
					(thickness 0.15)
				)
				(justify mirror)
			)
		)
		(property "MPN" "CR0402-FX-2201GLF"
			(at 101.40632 293.966336 0)
			(layer "B.Fab")
			(hide yes)
			(effects
				(font
					(size 1 1)
					(thickness 0.15)
				)
				(justify mirror)
			)
		)
		(property "Manufacturer" "Bourns"
			(at 101.40632 293.966336 0)
			(layer "B.Fab")
			(hide yes)
			(effects
				(font
					(size 1 1)
					(thickness 0.15)
				)
				(justify mirror)
			)
		)
		(property "Tolerance" "1%"
			(at 101.40632 293.966336 0)
			(layer "B.Fab")
			(hide yes)
			(effects
				(font
					(size 1 1)
					(thickness 0.15)
				)
				(justify mirror)
			)
		)
		(property "Val" "2k2"
			(at 101.40632 293.966336 0)
			(layer "B.Fab")
			(hide yes)
			(effects
				(font
					(size 1 1)
					(thickness 0.15)
				)
				(justify mirror)
			)
		)
		(sheetname "Ethernet")
		(sheetfile "ethernet.kicad_sch")
		(attr exclude_from_pos_files exclude_from_bom dnp)
		(fp_rect
			(start -0.93 0.47)
			(end 0.93 -0.47)
			(stroke
				(width 0.05)
				(type solid)
			)
			(fill no)
			(layer "B.CrtYd")
		)
		(fp_rect
			(start -0.5 0.25)
			(end 0.5 -0.25)
			(stroke
				(width 0.15)
				(type solid)
			)
			(fill no)
			(layer "B.Fab")
		)
		(pad "1" smd roundrect
			(at -0.485 0 270)
			(size 0.59 0.64)
			(layers "B.Cu" "B.Mask" "B.Paste")
			(roundrect_rratio 0.25)
			(net 37 "ETH_RXD2")
			(pintype "passive")
		)
		(pad "2" smd roundrect
			(at 0.485 0 270)
			(size 0.59 0.64)
			(layers "B.Cu" "B.Mask" "B.Paste")
			(roundrect_rratio 0.25)
			(net 5 "GND")
			(pintype "passive")
		)
	)
	(footprint "antmicro-footprints:R_0402_1005Metric"
		(layer "B.Cu")
		(at 199.836328 95.440008 -90)
		(descr "Resistor SMD 0402")
		(tags "resistor SMD 0402")
		(property "Reference" "R88"
			(at -1.140008 -1.263672 90)
			(layer "B.SilkS")
			(effects
				(font
					(size 0.7 0.7)
					(thickness 0.15)
				)
				(justify left bottom mirror)
			)
		)
		(property "Value" "R_2k2_0402"
			(at 0 -1.4 90)
			(layer "B.Fab")
			(effects
				(font
					(size 0.7 0.7)
					(thickness 0.15)
				)
				(justify left bottom mirror)
			)
		)
		(property "Description" "2k2 resistor in 0402 package with 1% tolerance"
			(at 0 0 270)
			(layer "F.Fab")
			(hide yes)
			(effects
				(font
					(size 1.27 1.27)
					(thickness 0.15)
				)
			)
		)
		(property "Author" "Antmicro"
			(at 104.39632 295.276336 0)
			(layer "B.Fab")
			(hide yes)
			(effects
				(font
					(size 1 1)
					(thickness 0.15)
				)
				(justify mirror)
			)
		)
		(property "License" "Apache-2.0"
			(at 104.39632 295.276336 0)
			(layer "B.Fab")
			(hide yes)
			(effects
				(font
					(size 1 1)
					(thickness 0.15)
				)
				(justify mirror)
			)
		)
		(property "MPN" "CR0402-FX-2201GLF"
			(at 104.39632 295.276336 0)
			(layer "B.Fab")
			(hide yes)
			(effects
				(font
					(size 1 1)
					(thickness 0.15)
				)
				(justify mirror)
			)
		)
		(property "Manufacturer" "Bourns"
			(at 104.39632 295.276336 0)
			(layer "B.Fab")
			(hide yes)
			(effects
				(font
					(size 1 1)
					(thickness 0.15)
				)
				(justify mirror)
			)
		)
		(property "Tolerance" "1%"
			(at 104.39632 295.276336 0)
			(layer "B.Fab")
			(hide yes)
			(effects
				(font
					(size 1 1)
					(thickness 0.15)
				)
				(justify mirror)
			)
		)
		(property "Val" "2k2"
			(at 104.39632 295.276336 0)
			(layer "B.Fab")
			(hide yes)
			(effects
				(font
					(size 1 1)
					(thickness 0.15)
				)
				(justify mirror)
			)
		)
		(sheetname "Ethernet")
		(sheetfile "ethernet.kicad_sch")
		(attr exclude_from_pos_files exclude_from_bom dnp)
		(fp_rect
			(start -0.93 0.47)
			(end 0.93 -0.47)
			(stroke
				(width 0.05)
				(type solid)
			)
			(fill no)
			(layer "B.CrtYd")
		)
		(fp_rect
			(start -0.5 0.25)
			(end 0.5 -0.25)
			(stroke
				(width 0.15)
				(type solid)
			)
			(fill no)
			(layer "B.Fab")
		)
		(pad "1" smd roundrect
			(at -0.485 0 270)
			(size 0.59 0.64)
			(layers "B.Cu" "B.Mask" "B.Paste")
			(roundrect_rratio 0.25)
			(net 33 "ETH_RXD3")
			(pintype "passive")
		)
		(pad "2" smd roundrect
			(at 0.485 0 270)
			(size 0.59 0.64)
			(layers "B.Cu" "B.Mask" "B.Paste")
			(roundrect_rratio 0.25)
			(net 5 "GND")
			(pintype "passive")
		)
	)
)
